# SCM (Grand Teton) — schematic netlist excerpt (pin names and nets, part order shuffled) for the footprints in the layout excerpt that follows; sources: Cadence DE-HDL packaged netlist, KiCad conversion of 12092022_DA0F0TMDCD0_F0T_Management_Board_D_brd_V3_OCP.brd

R284  Q_RES  75 1% CHIP  pkg 0402LF  page 49 : A = FM_UARTSW_MSB_N ; B = FM_UARTSW_MSB_R1_N
R323  Q_RES  0 5% CHIP  pkg 0402LF  page 36 : A = PWRGD_P1V2_AUX_R1 ; B = PWRGD_P1V2_AUX

(kicad_pcb
	(version 20260206)
	(generator "pcbnew")
	(generator_version "10.0")
	(general
		(thickness 1.6)
		(legacy_teardrops no)
	)
	(paper "A4")
	(title_block
		(title "12092022_DA0F0TMDCD0_F0T_Management_Board_D_brd_V3_OCP.brd")
		(comment 1 "Grand Teton / footprints 594-595 of 1440")
	)
	(layers
		(0 "F.Cu" signal "TOP")
		(4 "In1.Cu" signal "GND")
		(6 "In2.Cu" signal "IN1")
		(8 "In3.Cu" signal "GND1")
		(10 "In4.Cu" signal "IN2")
		(12 "In5.Cu" signal "VCC")
		(14 "In6.Cu" signal "VCC1")
		(16 "In7.Cu" signal "IN3")
		(18 "In8.Cu" signal "GND2")
		(20 "In9.Cu" signal "IN4")
		(22 "In10.Cu" signal "GND3")
		(2 "B.Cu" signal "BOTTOM")
		(9 "F.Adhes" user "F.Adhesive")
		(11 "B.Adhes" user "B.Adhesive")
		(13 "F.Paste" user "Package Geometry/Pastemask Top")
		(15 "B.Paste" user "Package Geometry/Pastemask Bottom")
		(5 "F.SilkS" user "Ref Des/Silkscreen Top")
		(7 "B.SilkS" user "Ref Des/Silkscreen Bottom")
		(1 "F.Mask" user "Board Geometry/Soldermask Top")
		(3 "B.Mask" user "Board Geometry/Soldermask Bottom")
		(17 "Dwgs.User" user "User.Drawings")
		(19 "Cmts.User" user "User.Comments")
		(21 "Eco1.User" user "User.Eco1")
		(23 "Eco2.User" user "User.Eco2")
		(25 "Edge.Cuts" user "Board Geometry/Outline")
		(27 "Margin" user)
		(31 "F.CrtYd" user "Package Geometry/Place Bound Top")
		(29 "B.CrtYd" user "Package Geometry/Place Bound Bottom")
		(35 "F.Fab" user "Ref Des/Assembly Top")
		(33 "B.Fab" user "Ref Des/Assembly Bottom")
	)
	(footprint ""
		(layer "F.Cu")
		(at 77.343 -20.193 180)
		(property "Reference" "R284"
			(at 0 0 180)
			(layer "F.SilkS")
			(hide yes)
			(effects
				(font
					(size 1.27 1.27)
				)
			)
		)
		(property "Value" ""
			(at 0 0 180)
			(layer "F.Fab")
			(effects
				(font
					(size 1.27 1.27)
				)
			)
		)
		(duplicate_pad_numbers_are_jumpers no)
		(fp_line
			(start 0.7874 0.4064)
			(end -0.7874 0.4064)
			(stroke
				(width 0.1524)
				(type default)
			)
			(layer "F.SilkS")
		)
		(fp_line
			(start 0.7874 -0.4064)
			(end 0.7874 0.4064)
			(stroke
				(width 0.1524)
				(type default)
			)
			(layer "F.SilkS")
		)
		(fp_line
			(start -0.7874 0.4064)
			(end -0.7874 -0.4064)
			(stroke
				(width 0.1524)
				(type default)
			)
			(layer "F.SilkS")
		)
		(fp_line
			(start -0.7874 -0.4064)
			(end 0.7874 -0.4064)
			(stroke
				(width 0.1524)
				(type default)
			)
			(layer "F.SilkS")
		)
		(fp_line
			(start 0.67945 0.3048)
			(end 0.120396 0.3048)
			(stroke
				(width 0.1)
				(type default)
			)
			(layer "F.Fab")
		)
		(fp_line
			(start 0.67945 -0.3048)
			(end 0.67945 0.3048)
			(stroke
				(width 0.1)
				(type default)
			)
			(layer "F.Fab")
		)
		(fp_line
			(start 0.12065 -0.2794)
			(end 0.12065 -0.3048)
			(stroke
				(width 0.1)
				(type default)
			)
			(layer "F.Fab")
		)
		(fp_line
			(start 0.12065 -0.3048)
			(end 0.67945 -0.3048)
			(stroke
				(width 0.1)
				(type default)
			)
			(layer "F.Fab")
		)
		(fp_line
			(start 0.120396 0.3048)
			(end 0.120396 0.2794)
			(stroke
				(width 0.1)
				(type default)
			)
			(layer "F.Fab")
		)
		(fp_line
			(start 0.120396 0.2794)
			(end -0.12065 0.2794)
			(stroke
				(width 0.1)
				(type default)
			)
			(layer "F.Fab")
		)
		(fp_line
			(start -0.12065 0.3048)
			(end -0.67945 0.3048)
			(stroke
				(width 0.1)
				(type default)
			)
			(layer "F.Fab")
		)
		(fp_line
			(start -0.12065 0.2794)
			(end -0.12065 0.3048)
			(stroke
				(width 0.1)
				(type default)
			)
			(layer "F.Fab")
		)
		(fp_line
			(start -0.12065 -0.2794)
			(end 0.12065 -0.2794)
			(stroke
				(width 0.1)
				(type default)
			)
			(layer "F.Fab")
		)
		(fp_line
			(start -0.12065 -0.305054)
			(end -0.12065 -0.2794)
			(stroke
				(width 0.1)
				(type default)
			)
			(layer "F.Fab")
		)
		(fp_line
			(start -0.67945 0.3048)
			(end -0.67945 -0.305054)
			(stroke
				(width 0.1)
				(type default)
			)
			(layer "F.Fab")
		)
		(fp_line
			(start -0.67945 -0.305054)
			(end -0.12065 -0.305054)
			(stroke
				(width 0.1)
				(type default)
			)
			(layer "F.Fab")
		)
		(pad "1" smd circle
			(at -0.40005 0 180)
			(size 0 0)
			(layers "F.Cu" "F.Mask" "F.Paste")
			(net "FM_UARTSW_MSB_N")
		)
		(pad "2" smd circle
			(at 0.40005 0 180)
			(size 0 0)
			(layers "F.Cu" "F.Mask" "F.Paste")
			(net "FM_UARTSW_MSB_R1_N")
		)
	)
	(footprint ""
		(layer "F.Cu")
		(at 20.066 -102.743 90)
		(property "Reference" "R323"
			(at 0 0 90)
			(layer "F.SilkS")
			(hide yes)
			(effects
				(font
					(size 1.27 1.27)
				)
			)
		)
		(property "Value" ""
			(at 0 0 90)
			(layer "F.Fab")
			(effects
				(font
					(size 1.27 1.27)
				)
			)
		)
		(duplicate_pad_numbers_are_jumpers no)
		(fp_line
			(start 0.7874 -0.4064)
			(end 0.7874 0.4064)
			(stroke
				(width 0.1524)
				(type default)
			)
			(layer "F.SilkS")
		)
		(fp_line
			(start -0.7874 -0.4064)
			(end 0.7874 -0.4064)
			(stroke
				(width 0.1524)
				(type default)
			)
			(layer "F.SilkS")
		)
		(fp_line
			(start 0.7874 0.4064)
			(end -0.7874 0.4064)
			(stroke
				(width 0.1524)
				(type default)
			)
			(layer "F.SilkS")
		)
		(fp_line
			(start -0.7874 0.4064)
			(end -0.7874 -0.4064)
			(stroke
				(width 0.1524)
				(type default)
			)
			(layer "F.SilkS")
		)
		(fp_line
			(start -0.12065 -0.305054)
			(end -0.12065 -0.2794)
			(stroke
				(width 0.1)
				(type default)
			)
			(layer "F.Fab")
		)
		(fp_line
			(start -0.67945 -0.305054)
			(end -0.12065 -0.305054)
			(stroke
				(width 0.1)
				(type default)
			)
			(layer "F.Fab")
		)
		(fp_line
			(start 0.67945 -0.3048)
			(end 0.67945 0.3048)
			(stroke
				(width 0.1)
				(type default)
			)
			(layer "F.Fab")
		)
		(fp_line
			(start 0.12065 -0.3048)
			(end 0.67945 -0.3048)
			(stroke
				(width 0.1)
				(type default)
			)
			(layer "F.Fab")
		)
		(fp_line
			(start 0.12065 -0.2794)
			(end 0.12065 -0.3048)
			(stroke
				(width 0.1)
				(type default)
			)
			(layer "F.Fab")
		)
		(fp_line
			(start -0.12065 -0.2794)
			(end 0.12065 -0.2794)
			(stroke
				(width 0.1)
				(type default)
			)
			(layer "F.Fab")
		)
		(fp_line
			(start 0.120396 0.2794)
			(end -0.12065 0.2794)
			(stroke
				(width 0.1)
				(type default)
			)
			(layer "F.Fab")
		)
		(fp_line
			(start -0.12065 0.2794)
			(end -0.12065 0.3048)
			(stroke
				(width 0.1)
				(type default)
			)
			(layer "F.Fab")
		)
		(fp_line
			(start 0.67945 0.3048)
			(end 0.120396 0.3048)
			(stroke
				(width 0.1)
				(type default)
			)
			(layer "F.Fab")
		)
		(fp_line
			(start 0.120396 0.3048)
			(end 0.120396 0.2794)
			(stroke
				(width 0.1)
				(type default)
			)
			(layer "F.Fab")
		)
		(fp_line
			(start -0.12065 0.3048)
			(end -0.67945 0.3048)
			(stroke
				(width 0.1)
				(type default)
			)
			(layer "F.Fab")
		)
		(fp_line
			(start -0.67945 0.3048)
			(end -0.67945 -0.305054)
			(stroke
				(width 0.1)
				(type default)
			)
			(layer "F.Fab")
		)
		(pad "1" smd circle
			(at -0.40005 0 90)
			(size 0 0)
			(layers "F.Cu" "F.Mask" "F.Paste")
			(net "PWRGD_P1V2_AUX_R1")
		)
		(pad "2" smd circle
			(at 0.40005 0 90)
			(size 0 0)
			(layers "F.Cu" "F.Mask" "F.Paste")
			(net "PWRGD_P1V2_AUX")
		)
	)
)
